(kicad_pcb
	(version 20260206)
	(generator "pcbnew")
	(generator_version "10.0")
	(general
		(thickness 1.6)
		(legacy_teardrops no)
	)
	(paper "A4")
	(title_block
		(title "15969-1a.1015WZS0858.brd")
		(comment 1 "Tioga Pass / footprints 102-109 of 295")
	)
	(layers
		(0 "F.Cu" signal "TOP")
		(4 "In1.Cu" signal "L2GND")
		(6 "In2.Cu" signal "L3")
		(8 "In3.Cu" signal "L4")
		(10 "In4.Cu" signal "L5GND")
		(2 "B.Cu" signal "BOTTOM")
		(9 "F.Adhes" user "F.Adhesive")
		(11 "B.Adhes" user "B.Adhesive")
		(13 "F.Paste" user "Package Geometry/Pastemask Top")
		(15 "B.Paste" user "Package Geometry/Pastemask Bottom")
		(5 "F.SilkS" user "Ref Des/Silkscreen Top")
		(7 "B.SilkS" user "Ref Des/Silkscreen Bottom")
		(1 "F.Mask" user "Board Geometry/Soldermask Top")
		(3 "B.Mask" user "Board Geometry/Soldermask Bottom")
		(17 "Dwgs.User" user "User.Drawings")
		(19 "Cmts.User" user "User.Comments")
		(21 "Eco1.User" user "User.Eco1")
		(23 "Eco2.User" user "User.Eco2")
		(25 "Edge.Cuts" user "Board Geometry/Outline")
		(27 "Margin" user)
		(31 "F.CrtYd" user "Package Geometry/Place Bound Top")
		(29 "B.CrtYd" user "Package Geometry/Place Bound Bottom")
		(35 "F.Fab" user "Ref Des/Assembly Top")
		(33 "B.Fab" user "Ref Des/Assembly Bottom")
	)
	(footprint ""
		(layer "F.Cu")
		(at 128.8796 -30.861 180)
		(property "Reference" "RU24"
			(at 0 0 180)
			(layer "F.SilkS")
			(hide yes)
			(effects
				(font
					(size 1.27 1.27)
				)
			)
		)
		(property "Value" "12KR2F-L-GP"
			(at 0.064008 -3.993896 180)
			(unlocked yes)
			(layer "F.Fab")
			(hide yes)
			(effects
				(font
					(size 1.016 1.016)
					(thickness 0.1524)
				)
			)
		)
		(property "Device Type" "R402H16"
			(at 0.064008 -5.517896 180)
			(unlocked yes)
			(layer "F.Fab")
			(hide yes)
			(effects
				(font
					(size 1.016 1.016)
					(thickness 0.1524)
				)
			)
		)
		(duplicate_pad_numbers_are_jumpers no)
		(fp_line
			(start 0.508 -0.9398)
			(end -0.508 -0.9398)
			(stroke
				(width 0.1524)
				(type default)
			)
			(layer "F.SilkS")
		)
		(fp_line
			(start -0.508 -0.9398)
			(end -0.508 0.9398)
			(stroke
				(width 0.1524)
				(type default)
			)
			(layer "F.SilkS")
		)
		(fp_rect
			(start -0.508 0.9398)
			(end 0.508 -0.9398)
			(stroke
				(width 0)
				(type default)
			)
			(fill no)
			(layer "F.CrtYd")
		)
		(fp_rect
			(start -0.508 0.9398)
			(end 0.508 -0.9398)
			(stroke
				(width 0)
				(type default)
			)
			(fill no)
			(layer "F.Fab")
		)
		(pad "1" smd custom
			(at 0 -0.4445 180)
			(size 0.1397 0.1397)
			(layers "F.Cu" "F.Mask" "F.Paste")
			(net "RBIAS")
			(options
				(clearance outline)
				(anchor circle)
			)
			(primitives
				(gr_poly
					(pts
						(arc
							(start -0.1778 -0.2794)
							(mid -0.249642 -0.249642)
							(end -0.2794 -0.1778)
						)
						(arc
							(start -0.2794 0.1778)
							(mid -0.249642 0.249642)
							(end -0.1778 0.2794)
						)
						(arc
							(start 0.1778 0.2794)
							(mid 0.249642 0.249642)
							(end 0.2794 0.1778)
						)
						(arc
							(start 0.2794 -0.1778)
							(mid 0.249642 -0.249642)
							(end 0.1778 -0.2794)
						)
					)
					(width 0)
					(fill yes)
				)
			)
		)
		(pad "2" smd custom
			(at 0 0.4445 180)
			(size 0.1397 0.1397)
			(layers "F.Cu" "F.Mask" "F.Paste")
			(net "GND")
			(options
				(clearance outline)
				(anchor circle)
			)
			(primitives
				(gr_poly
					(pts
						(arc
							(start -0.1778 -0.2794)
							(mid -0.249642 -0.249642)
							(end -0.2794 -0.1778)
						)
						(arc
							(start -0.2794 0.1778)
							(mid -0.249642 0.249642)
							(end -0.1778 0.2794)
						)
						(arc
							(start 0.1778 0.2794)
							(mid 0.249642 0.249642)
							(end 0.2794 0.1778)
						)
						(arc
							(start 0.2794 -0.1778)
							(mid 0.249642 -0.249642)
							(end 0.1778 -0.2794)
						)
					)
					(width 0)
					(fill yes)
				)
			)
		)
	)
	(footprint ""
		(layer "F.Cu")
		(at 23.7998 4.1783 90)
		(property "Reference" "R56"
			(at 0 0 90)
			(layer "F.SilkS")
			(hide yes)
			(effects
				(font
					(size 1.27 1.27)
				)
			)
		)
		(property "Value" "4K7R2F-GP"
			(at 0.064008 -3.993896 90)
			(unlocked yes)
			(layer "F.Fab")
			(hide yes)
			(effects
				(font
					(size 1.016 1.016)
					(thickness 0.1524)
				)
			)
		)
		(property "Device Type" "R402H16"
			(at 0.064008 -5.517896 90)
			(unlocked yes)
			(layer "F.Fab")
			(hide yes)
			(effects
				(font
					(size 1.016 1.016)
					(thickness 0.1524)
				)
			)
		)
		(duplicate_pad_numbers_are_jumpers no)
		(fp_line
			(start 0.508 -0.9398)
			(end -0.508 -0.9398)
			(stroke
				(width 0.1524)
				(type default)
			)
			(layer "F.SilkS")
		)
		(fp_line
			(start -0.508 -0.9398)
			(end -0.508 0.9398)
			(stroke
				(width 0.1524)
				(type default)
			)
			(layer "F.SilkS")
		)
		(fp_rect
			(start -0.508 0.9398)
			(end 0.508 -0.9398)
			(stroke
				(width 0)
				(type default)
			)
			(fill no)
			(layer "F.CrtYd")
		)
		(fp_rect
			(start -0.508 0.9398)
			(end 0.508 -0.9398)
			(stroke
				(width 0)
				(type default)
			)
			(fill no)
			(layer "F.Fab")
		)
		(pad "1" smd custom
			(at 0 -0.4445 90)
			(size 0.1397 0.1397)
			(layers "F.Cu" "F.Mask" "F.Paste")
			(net "P3V3_STBY")
			(options
				(clearance outline)
				(anchor circle)
			)
			(primitives
				(gr_poly
					(pts
						(arc
							(start -0.1778 -0.2794)
							(mid -0.249642 -0.249642)
							(end -0.2794 -0.1778)
						)
						(arc
							(start -0.2794 0.1778)
							(mid -0.249642 0.249642)
							(end -0.1778 0.2794)
						)
						(arc
							(start 0.1778 0.2794)
							(mid 0.249642 0.249642)
							(end 0.2794 0.1778)
						)
						(arc
							(start 0.2794 -0.1778)
							(mid 0.249642 -0.249642)
							(end 0.1778 -0.2794)
						)
					)
					(width 0)
					(fill yes)
				)
			)
		)
		(pad "2" smd custom
			(at 0 0.4445 90)
			(size 0.1397 0.1397)
			(layers "F.Cu" "F.Mask" "F.Paste")
			(net "FM_SLT_CFG0")
			(options
				(clearance outline)
				(anchor circle)
			)
			(primitives
				(gr_poly
					(pts
						(arc
							(start -0.1778 -0.2794)
							(mid -0.249642 -0.249642)
							(end -0.2794 -0.1778)
						)
						(arc
							(start -0.2794 0.1778)
							(mid -0.249642 0.249642)
							(end -0.1778 0.2794)
						)
						(arc
							(start 0.1778 0.2794)
							(mid 0.249642 0.249642)
							(end 0.2794 0.1778)
						)
						(arc
							(start 0.2794 -0.1778)
							(mid 0.249642 -0.249642)
							(end 0.1778 -0.2794)
						)
					)
					(width 0)
					(fill yes)
				)
			)
		)
	)
	(footprint ""
		(layer "F.Cu")
		(at 95.5802 -16.8656)
		(property "Reference" "R69"
			(at 0 0 0)
			(layer "F.SilkS")
			(hide yes)
			(effects
				(font
					(size 1.27 1.27)
				)
			)
		)
		(property "Value" "0R2F-1-GP"
			(at 0.064008 -3.993896 0)
			(unlocked yes)
			(layer "F.Fab")
			(hide yes)
			(effects
				(font
					(size 1.016 1.016)
					(thickness 0.1524)
				)
			)
		)
		(property "Device Type" "R402H16"
			(at 0.064008 -5.517896 0)
			(unlocked yes)
			(layer "F.Fab")
			(hide yes)
			(effects
				(font
					(size 1.016 1.016)
					(thickness 0.1524)
				)
			)
		)
		(duplicate_pad_numbers_are_jumpers no)
		(fp_line
			(start -0.508 -0.9398)
			(end -0.508 0.9398)
			(stroke
				(width 0.1524)
				(type default)
			)
			(layer "F.SilkS")
		)
		(fp_line
			(start 0.508 -0.9398)
			(end -0.508 -0.9398)
			(stroke
				(width 0.1524)
				(type default)
			)
			(layer "F.SilkS")
		)
		(fp_rect
			(start -0.508 0.9398)
			(end 0.508 -0.9398)
			(stroke
				(width 0)
				(type default)
			)
			(fill no)
			(layer "F.CrtYd")
		)
		(fp_rect
			(start -0.508 0.9398)
			(end 0.508 -0.9398)
			(stroke
				(width 0)
				(type default)
			)
			(fill no)
			(layer "F.Fab")
		)
		(pad "1" smd custom
			(at 0 -0.4445)
			(size 0.1397 0.1397)
			(layers "F.Cu" "F.Mask" "F.Paste")
			(net "PERST_SLOT_N")
			(options
				(clearance outline)
				(anchor circle)
			)
			(primitives
				(gr_poly
					(pts
						(arc
							(start -0.1778 -0.2794)
							(mid -0.249642 -0.249642)
							(end -0.2794 -0.1778)
						)
						(arc
							(start -0.2794 0.1778)
							(mid -0.249642 0.249642)
							(end -0.1778 0.2794)
						)
						(arc
							(start 0.1778 0.2794)
							(mid 0.249642 0.249642)
							(end 0.2794 0.1778)
						)
						(arc
							(start 0.2794 -0.1778)
							(mid 0.249642 -0.249642)
							(end 0.1778 -0.2794)
						)
					)
					(width 0)
					(fill yes)
				)
			)
		)
		(pad "2" smd custom
			(at 0 0.4445)
			(size 0.1397 0.1397)
			(layers "F.Cu" "F.Mask" "F.Paste")
			(net "RESET_BUF_N_SLOT2")
			(options
				(clearance outline)
				(anchor circle)
			)
			(primitives
				(gr_poly
					(pts
						(arc
							(start -0.1778 -0.2794)
							(mid -0.249642 -0.249642)
							(end -0.2794 -0.1778)
						)
						(arc
							(start -0.2794 0.1778)
							(mid -0.249642 0.249642)
							(end -0.1778 0.2794)
						)
						(arc
							(start 0.1778 0.2794)
							(mid 0.249642 0.249642)
							(end 0.2794 0.1778)
						)
						(arc
							(start 0.2794 -0.1778)
							(mid 0.249642 -0.249642)
							(end 0.1778 -0.2794)
						)
					)
					(width 0)
					(fill yes)
				)
			)
		)
	)
	(footprint ""
		(layer "F.Cu")
		(at 26.2382 -23.749 180)
		(property "Reference" "R91"
			(at 0 0 180)
			(layer "F.SilkS")
			(hide yes)
			(effects
				(font
					(size 1.27 1.27)
				)
			)
		)
		(property "Value" "10KR2F-2-GP"
			(at 0.064008 -3.993896 180)
			(unlocked yes)
			(layer "F.Fab")
			(hide yes)
			(effects
				(font
					(size 1.016 1.016)
					(thickness 0.1524)
				)
			)
		)
		(property "Device Type" "R402H16"
			(at 0.064008 -5.517896 180)
			(unlocked yes)
			(layer "F.Fab")
			(hide yes)
			(effects
				(font
					(size 1.016 1.016)
					(thickness 0.1524)
				)
			)
		)
		(duplicate_pad_numbers_are_jumpers no)
		(fp_line
			(start 0.508 -0.9398)
			(end -0.508 -0.9398)
			(stroke
				(width 0.1524)
				(type default)
			)
			(layer "F.SilkS")
		)
		(fp_line
			(start -0.508 -0.9398)
			(end -0.508 0.9398)
			(stroke
				(width 0.1524)
				(type default)
			)
			(layer "F.SilkS")
		)
		(fp_rect
			(start -0.508 0.9398)
			(end 0.508 -0.9398)
			(stroke
				(width 0)
				(type default)
			)
			(fill no)
			(layer "F.CrtYd")
		)
		(fp_rect
			(start -0.508 0.9398)
			(end 0.508 -0.9398)
			(stroke
				(width 0)
				(type default)
			)
			(fill no)
			(layer "F.Fab")
		)
		(pad "1" smd custom
			(at 0 -0.4445 180)
			(size 0.1397 0.1397)
			(layers "F.Cu" "F.Mask" "F.Paste")
			(net "P3V3_STBY")
			(options
				(clearance outline)
				(anchor circle)
			)
			(primitives
				(gr_poly
					(pts
						(arc
							(start -0.1778 -0.2794)
							(mid -0.249642 -0.249642)
							(end -0.2794 -0.1778)
						)
						(arc
							(start -0.2794 0.1778)
							(mid -0.249642 0.249642)
							(end -0.1778 0.2794)
						)
						(arc
							(start 0.1778 0.2794)
							(mid 0.249642 0.249642)
							(end 0.2794 0.1778)
						)
						(arc
							(start 0.2794 -0.1778)
							(mid 0.249642 -0.249642)
							(end 0.1778 -0.2794)
						)
					)
					(width 0)
					(fill yes)
				)
			)
		)
		(pad "2" smd custom
			(at 0 0.4445 180)
			(size 0.1397 0.1397)
			(layers "F.Cu" "F.Mask" "F.Paste")
			(net "SLOT3_VMONITOR_A1")
			(options
				(clearance outline)
				(anchor circle)
			)
			(primitives
				(gr_poly
					(pts
						(arc
							(start -0.1778 -0.2794)
							(mid -0.249642 -0.249642)
							(end -0.2794 -0.1778)
						)
						(arc
							(start -0.2794 0.1778)
							(mid -0.249642 0.249642)
							(end -0.1778 0.2794)
						)
						(arc
							(start 0.1778 0.2794)
							(mid 0.249642 0.249642)
							(end 0.2794 0.1778)
						)
						(arc
							(start 0.2794 -0.1778)
							(mid 0.249642 -0.249642)
							(end 0.1778 -0.2794)
						)
					)
					(width 0)
					(fill yes)
				)
			)
		)
	)
	(footprint ""
		(layer "F.Cu")
		(at 115.5446 -3.7592)
		(property "Reference" "TP16"
			(at 0 0 0)
			(layer "F.SilkS")
			(hide yes)
			(effects
				(font
					(size 1.27 1.27)
				)
			)
		)
		(property "Value" "TPAD24"
			(at 0 -1.6129 0)
			(unlocked yes)
			(layer "F.Fab")
			(hide yes)
			(effects
				(font
					(size 1.016 1.016)
					(thickness 0.1524)
				)
			)
		)
		(property "Device Type" "TPAD24"
			(at 0 -3.1369 0)
			(unlocked yes)
			(layer "F.Fab")
			(hide yes)
			(effects
				(font
					(size 1.016 1.016)
					(thickness 0.1524)
				)
			)
		)
		(duplicate_pad_numbers_are_jumpers no)
		(fp_poly
			(pts
				(arc
					(start 0.3048 0)
					(mid -0.3048 0)
					(end 0.3048 0)
				)
			)
			(stroke
				(width 0)
				(type default)
			)
			(fill no)
			(layer "F.CrtYd")
		)
		(fp_poly
			(pts
				(arc
					(start 0.6096 0)
					(mid -0.6096 0)
					(end 0.6096 0)
				)
			)
			(stroke
				(width 0)
				(type default)
			)
			(fill no)
			(layer "F.Fab")
		)
		(pad "1" smd circle
			(at 0 0)
			(size 0.6096 0.6096)
			(layers "F.Cu" "F.Mask" "F.Paste")
			(net "TP_RSVD_SLOT2_PIN82")
		)
	)
	(footprint ""
		(layer "F.Cu")
		(at 130.4036 -25.527 90)
		(property "Reference" "RU50"
			(at 0 0 90)
			(layer "F.SilkS")
			(hide yes)
			(effects
				(font
					(size 1.27 1.27)
				)
			)
		)
		(property "Value" "100KR2F-L1-GP"
			(at 0.064008 -3.993896 90)
			(unlocked yes)
			(layer "F.Fab")
			(hide yes)
			(effects
				(font
					(size 1.016 1.016)
					(thickness 0.1524)
				)
			)
		)
		(property "Device Type" "R402H16"
			(at 0.064008 -5.517896 90)
			(unlocked yes)
			(layer "F.Fab")
			(hide yes)
			(effects
				(font
					(size 1.016 1.016)
					(thickness 0.1524)
				)
			)
		)
		(duplicate_pad_numbers_are_jumpers no)
		(fp_line
			(start 0.508 -0.9398)
			(end -0.508 -0.9398)
			(stroke
				(width 0.1524)
				(type default)
			)
			(layer "F.SilkS")
		)
		(fp_line
			(start -0.508 -0.9398)
			(end -0.508 0.9398)
			(stroke
				(width 0.1524)
				(type default)
			)
			(layer "F.SilkS")
		)
		(fp_rect
			(start -0.508 0.9398)
			(end 0.508 -0.9398)
			(stroke
				(width 0)
				(type default)
			)
			(fill no)
			(layer "F.CrtYd")
		)
		(fp_rect
			(start -0.508 0.9398)
			(end 0.508 -0.9398)
			(stroke
				(width 0)
				(type default)
			)
			(fill no)
			(layer "F.Fab")
		)
		(pad "1" smd custom
			(at 0 -0.4445 90)
			(size 0.1397 0.1397)
			(layers "F.Cu" "F.Mask" "F.Paste")
			(net "NON_REM0")
			(options
				(clearance outline)
				(anchor circle)
			)
			(primitives
				(gr_poly
					(pts
						(arc
							(start -0.1778 -0.2794)
							(mid -0.249642 -0.249642)
							(end -0.2794 -0.1778)
						)
						(arc
							(start -0.2794 0.1778)
							(mid -0.249642 0.249642)
							(end -0.1778 0.2794)
						)
						(arc
							(start 0.1778 0.2794)
							(mid 0.249642 0.249642)
							(end 0.2794 0.1778)
						)
						(arc
							(start 0.2794 -0.1778)
							(mid 0.249642 -0.249642)
							(end 0.1778 -0.2794)
						)
					)
					(width 0)
					(fill yes)
				)
			)
		)
		(pad "2" smd custom
			(at 0 0.4445 90)
			(size 0.1397 0.1397)
			(layers "F.Cu" "F.Mask" "F.Paste")
			(net "P3V3_USB_HUB")
			(options
				(clearance outline)
				(anchor circle)
			)
			(primitives
				(gr_poly
					(pts
						(arc
							(start -0.1778 -0.2794)
							(mid -0.249642 -0.249642)
							(end -0.2794 -0.1778)
						)
						(arc
							(start -0.2794 0.1778)
							(mid -0.249642 0.249642)
							(end -0.1778 0.2794)
						)
						(arc
							(start 0.1778 0.2794)
							(mid 0.249642 0.249642)
							(end 0.2794 0.1778)
						)
						(arc
							(start 0.2794 -0.1778)
							(mid 0.249642 -0.249642)
							(end 0.1778 -0.2794)
						)
					)
					(width 0)
					(fill yes)
				)
			)
		)
	)
	(footprint ""
		(layer "F.Cu")
		(at 117.6528 -19.0246 180)
		(property "Reference" "R115"
			(at 0 0 180)
			(layer "F.SilkS")
			(hide yes)
			(effects
				(font
					(size 1.27 1.27)
				)
			)
		)
		(property "Value" "10KR2F-2-GP"
			(at 0.064008 -3.993896 180)
			(unlocked yes)
			(layer "F.Fab")
			(hide yes)
			(effects
				(font
					(size 1.016 1.016)
					(thickness 0.1524)
				)
			)
		)
		(property "Device Type" "R402H16"
			(at 0.064008 -5.517896 180)
			(unlocked yes)
			(layer "F.Fab")
			(hide yes)
			(effects
				(font
					(size 1.016 1.016)
					(thickness 0.1524)
				)
			)
		)
		(duplicate_pad_numbers_are_jumpers no)
		(fp_line
			(start 0.508 -0.9398)
			(end -0.508 -0.9398)
			(stroke
				(width 0.1524)
				(type default)
			)
			(layer "F.SilkS")
		)
		(fp_line
			(start -0.508 -0.9398)
			(end -0.508 0.9398)
			(stroke
				(width 0.1524)
				(type default)
			)
			(layer "F.SilkS")
		)
		(fp_rect
			(start -0.508 0.9398)
			(end 0.508 -0.9398)
			(stroke
				(width 0)
				(type default)
			)
			(fill no)
			(layer "F.CrtYd")
		)
		(fp_rect
			(start -0.508 0.9398)
			(end 0.508 -0.9398)
			(stroke
				(width 0)
				(type default)
			)
			(fill no)
			(layer "F.Fab")
		)
		(pad "1" smd custom
			(at 0 -0.4445 180)
			(size 0.1397 0.1397)
			(layers "F.Cu" "F.Mask" "F.Paste")
			(net "GPIO_B_EXP_A2")
			(options
				(clearance outline)
				(anchor circle)
			)
			(primitives
				(gr_poly
					(pts
						(arc
							(start -0.1778 -0.2794)
							(mid -0.249642 -0.249642)
							(end -0.2794 -0.1778)
						)
						(arc
							(start -0.2794 0.1778)
							(mid -0.249642 0.249642)
							(end -0.1778 0.2794)
						)
						(arc
							(start 0.1778 0.2794)
							(mid 0.249642 0.249642)
							(end 0.2794 0.1778)
						)
						(arc
							(start 0.2794 -0.1778)
							(mid 0.249642 -0.249642)
							(end 0.1778 -0.2794)
						)
					)
					(width 0)
					(fill yes)
				)
			)
		)
		(pad "2" smd custom
			(at 0 0.4445 180)
			(size 0.1397 0.1397)
			(layers "F.Cu" "F.Mask" "F.Paste")
			(net "GND")
			(options
				(clearance outline)
				(anchor circle)
			)
			(primitives
				(gr_poly
					(pts
						(arc
							(start -0.1778 -0.2794)
							(mid -0.249642 -0.249642)
							(end -0.2794 -0.1778)
						)
						(arc
							(start -0.2794 0.1778)
							(mid -0.249642 0.249642)
							(end -0.1778 0.2794)
						)
						(arc
							(start 0.1778 0.2794)
							(mid 0.249642 0.249642)
							(end 0.2794 0.1778)
						)
						(arc
							(start 0.2794 -0.1778)
							(mid 0.249642 -0.249642)
							(end 0.1778 -0.2794)
						)
					)
					(width 0)
					(fill yes)
				)
			)
		)
	)
	(footprint ""
		(layer "F.Cu")
		(at 131.7244 -13.589 -90)
		(property "Reference" "R124"
			(at 0 0 270)
			(layer "F.SilkS")
			(hide yes)
			(effects
				(font
					(size 1.27 1.27)
				)
			)
		)
		(property "Value" "10KR2F-2-GP"
			(at 0.064008 -3.993896 270)
			(unlocked yes)
			(layer "F.Fab")
			(hide yes)
			(effects
				(font
					(size 1.016 1.016)
					(thickness 0.1524)
				)
			)
		)
		(property "Device Type" "R402H16"
			(at 0.064008 -5.517896 270)
			(unlocked yes)
			(layer "F.Fab")
			(hide yes)
			(effects
				(font
					(size 1.016 1.016)
					(thickness 0.1524)
				)
			)
		)
		(duplicate_pad_numbers_are_jumpers no)
		(fp_line
			(start -0.508 -0.9398)
			(end -0.508 0.9398)
			(stroke
				(width 0.1524)
				(type default)
			)
			(layer "F.SilkS")
		)
		(fp_line
			(start 0.508 -0.9398)
			(end -0.508 -0.9398)
			(stroke
				(width 0.1524)
				(type default)
			)
			(layer "F.SilkS")
		)
		(fp_rect
			(start -0.508 0.9398)
			(end 0.508 -0.9398)
			(stroke
				(width 0)
				(type default)
			)
			(fill no)
			(layer "F.CrtYd")
		)
		(fp_rect
			(start -0.508 0.9398)
			(end 0.508 -0.9398)
			(stroke
				(width 0)
				(type default)
			)
			(fill no)
			(layer "F.Fab")
		)
		(pad "1" smd custom
			(at 0 -0.4445 270)
			(size 0.1397 0.1397)
			(layers "F.Cu" "F.Mask" "F.Paste")
			(net "P3V3_STBY")
			(options
				(clearance outline)
				(anchor circle)
			)
			(primitives
				(gr_poly
					(pts
						(arc
							(start -0.1778 -0.2794)
							(mid -0.249642 -0.249642)
							(end -0.2794 -0.1778)
						)
						(arc
							(start -0.2794 0.1778)
							(mid -0.249642 0.249642)
							(end -0.1778 0.2794)
						)
						(arc
							(start 0.1778 0.2794)
							(mid 0.249642 0.249642)
							(end 0.2794 0.1778)
						)
						(arc
							(start 0.2794 -0.1778)
							(mid 0.249642 -0.249642)
							(end 0.1778 -0.2794)
						)
					)
					(width 0)
					(fill yes)
				)
			)
		)
		(pad "2" smd custom
			(at 0 0.4445 270)
			(size 0.1397 0.1397)
			(layers "F.Cu" "F.Mask" "F.Paste")
			(net "GPIO_B_IO1_4")
			(options
				(clearance outline)
				(anchor circle)
			)
			(primitives
				(gr_poly
					(pts
						(arc
							(start -0.1778 -0.2794)
							(mid -0.249642 -0.249642)
							(end -0.2794 -0.1778)
						)
						(arc
							(start -0.2794 0.1778)
							(mid -0.249642 0.249642)
							(end -0.1778 0.2794)
						)
						(arc
							(start 0.1778 0.2794)
							(mid 0.249642 0.249642)
							(end 0.2794 0.1778)
						)
						(arc
							(start 0.2794 -0.1778)
							(mid 0.249642 -0.249642)
							(end 0.1778 -0.2794)
						)
					)
					(width 0)
					(fill yes)
				)
			)
		)
	)
)
